(kicad_pcb
	(version 20260206)
	(generator "pcbnew")
	(generator_version "10.0")
	(general
		(thickness 1.6)
		(legacy_teardrops no)
	)
	(paper "A4")
	(title_block
		(title "03242023_DA0F0TMBIJ0_F0T_Motherboard_J_brd_V01_OCP.brd")
		(comment 1 "Grand Teton / footprints 315-321 of 6105")
	)
	(layers
		(0 "F.Cu" signal "TOP")
		(4 "In1.Cu" signal "GND")
		(6 "In2.Cu" signal "IN1")
		(8 "In3.Cu" signal "GND1")
		(10 "In4.Cu" signal "IN2")
		(12 "In5.Cu" signal "GND2")
		(14 "In6.Cu" signal "IN3")
		(16 "In7.Cu" signal "GND3")
		(18 "In8.Cu" signal "VCC")
		(20 "In9.Cu" signal "VCC1")
		(22 "In10.Cu" signal "GND4")
		(24 "In11.Cu" signal "IN4")
		(26 "In12.Cu" signal "GND5")
		(28 "In13.Cu" signal "IN5")
		(30 "In14.Cu" signal "GND6")
		(32 "In15.Cu" signal "IN6")
		(34 "In16.Cu" signal "GND7")
		(2 "B.Cu" signal "BOTTOM")
		(9 "F.Adhes" user "F.Adhesive")
		(11 "B.Adhes" user "B.Adhesive")
		(13 "F.Paste" user "Package Geometry/Pastemask Top")
		(15 "B.Paste" user "Package Geometry/Pastemask Bottom")
		(5 "F.SilkS" user "Ref Des/Silkscreen Top")
		(7 "B.SilkS" user "Ref Des/Silkscreen Bottom")
		(1 "F.Mask" user "Board Geometry/Soldermask Top")
		(3 "B.Mask" user "Board Geometry/Soldermask Bottom")
		(17 "Dwgs.User" user "User.Drawings")
		(19 "Cmts.User" user "User.Comments")
		(21 "Eco1.User" user "User.Eco1")
		(23 "Eco2.User" user "User.Eco2")
		(25 "Edge.Cuts" user "Board Geometry/Outline")
		(27 "Margin" user)
		(31 "F.CrtYd" user "Package Geometry/Place Bound Top")
		(29 "B.CrtYd" user "Package Geometry/Place Bound Bottom")
		(35 "F.Fab" user "Ref Des/Assembly Top")
		(33 "B.Fab" user "Ref Des/Assembly Bottom")
	)
	(footprint ""
		(layer "F.Cu")
		(at 39.827454 -111.606838)
		(property "Reference" "R3866"
			(at 0 0 0)
			(layer "F.SilkS")
			(hide yes)
			(effects
				(font
					(size 1.27 1.27)
				)
			)
		)
		(property "Value" ""
			(at 0 0 0)
			(layer "F.Fab")
			(effects
				(font
					(size 1.27 1.27)
				)
			)
		)
		(duplicate_pad_numbers_are_jumpers no)
		(fp_line
			(start -0.7874 -0.4064)
			(end 0.7874 -0.4064)
			(stroke
				(width 0.1524)
				(type default)
			)
			(layer "F.SilkS")
		)
		(fp_line
			(start -0.7874 0.4064)
			(end -0.7874 -0.4064)
			(stroke
				(width 0.1524)
				(type default)
			)
			(layer "F.SilkS")
		)
		(fp_line
			(start 0.7874 -0.4064)
			(end 0.7874 0.4064)
			(stroke
				(width 0.1524)
				(type default)
			)
			(layer "F.SilkS")
		)
		(fp_line
			(start 0.7874 0.4064)
			(end -0.7874 0.4064)
			(stroke
				(width 0.1524)
				(type default)
			)
			(layer "F.SilkS")
		)
		(fp_line
			(start -0.67945 -0.305054)
			(end -0.12065 -0.305054)
			(stroke
				(width 0.1)
				(type default)
			)
			(layer "F.Fab")
		)
		(fp_line
			(start -0.67945 0.3048)
			(end -0.67945 -0.305054)
			(stroke
				(width 0.1)
				(type default)
			)
			(layer "F.Fab")
		)
		(fp_line
			(start -0.12065 -0.305054)
			(end -0.12065 -0.2794)
			(stroke
				(width 0.1)
				(type default)
			)
			(layer "F.Fab")
		)
		(fp_line
			(start -0.12065 -0.2794)
			(end 0.12065 -0.2794)
			(stroke
				(width 0.1)
				(type default)
			)
			(layer "F.Fab")
		)
		(fp_line
			(start -0.12065 0.2794)
			(end -0.12065 0.3048)
			(stroke
				(width 0.1)
				(type default)
			)
			(layer "F.Fab")
		)
		(fp_line
			(start -0.12065 0.3048)
			(end -0.67945 0.3048)
			(stroke
				(width 0.1)
				(type default)
			)
			(layer "F.Fab")
		)
		(fp_line
			(start 0.120396 0.2794)
			(end -0.12065 0.2794)
			(stroke
				(width 0.1)
				(type default)
			)
			(layer "F.Fab")
		)
		(fp_line
			(start 0.120396 0.3048)
			(end 0.120396 0.2794)
			(stroke
				(width 0.1)
				(type default)
			)
			(layer "F.Fab")
		)
		(fp_line
			(start 0.12065 -0.3048)
			(end 0.67945 -0.3048)
			(stroke
				(width 0.1)
				(type default)
			)
			(layer "F.Fab")
		)
		(fp_line
			(start 0.12065 -0.2794)
			(end 0.12065 -0.3048)
			(stroke
				(width 0.1)
				(type default)
			)
			(layer "F.Fab")
		)
		(fp_line
			(start 0.67945 -0.3048)
			(end 0.67945 0.3048)
			(stroke
				(width 0.1)
				(type default)
			)
			(layer "F.Fab")
		)
		(fp_line
			(start 0.67945 0.3048)
			(end 0.120396 0.3048)
			(stroke
				(width 0.1)
				(type default)
			)
			(layer "F.Fab")
		)
		(pad "1" smd rect
			(at -0.40005 0 180)
			(size 0.4572 0.508)
			(layers "F.Cu" "F.Mask" "F.Paste")
			(net "P12V_OCP_SFF_ISENSE_MPS_TIC")
		)
		(pad "2" smd rect
			(at 0.40005 0 180)
			(size 0.4572 0.508)
			(layers "F.Cu" "F.Mask" "F.Paste")
			(net "P12V_OCP_SFF_ISENSE_TIC")
		)
	)
	(footprint ""
		(layer "F.Cu")
		(at 115.052094 -338.17814 -90)
		(property "Reference" "PC532"
			(at 0 0 270)
			(layer "F.SilkS")
			(hide yes)
			(effects
				(font
					(size 1.27 1.27)
				)
			)
		)
		(property "Value" ""
			(at 0 0 270)
			(layer "F.Fab")
			(effects
				(font
					(size 1.27 1.27)
				)
			)
		)
		(duplicate_pad_numbers_are_jumpers no)
		(fp_line
			(start -0.7874 0.4064)
			(end -0.7874 -0.4064)
			(stroke
				(width 0.1524)
				(type default)
			)
			(layer "F.SilkS")
		)
		(fp_line
			(start 0.7874 0.4064)
			(end -0.7874 0.4064)
			(stroke
				(width 0.1524)
				(type default)
			)
			(layer "F.SilkS")
		)
		(fp_line
			(start -0.7874 -0.4064)
			(end 0.7874 -0.4064)
			(stroke
				(width 0.1524)
				(type default)
			)
			(layer "F.SilkS")
		)
		(fp_line
			(start 0.7874 -0.4064)
			(end 0.7874 0.4064)
			(stroke
				(width 0.1524)
				(type default)
			)
			(layer "F.SilkS")
		)
		(fp_line
			(start -0.67945 0.3048)
			(end -0.67945 -0.305054)
			(stroke
				(width 0.1)
				(type default)
			)
			(layer "F.Fab")
		)
		(fp_line
			(start -0.12065 0.3048)
			(end -0.67945 0.3048)
			(stroke
				(width 0.1)
				(type default)
			)
			(layer "F.Fab")
		)
		(fp_line
			(start 0.120396 0.3048)
			(end 0.120396 0.2794)
			(stroke
				(width 0.1)
				(type default)
			)
			(layer "F.Fab")
		)
		(fp_line
			(start 0.67945 0.3048)
			(end 0.120396 0.3048)
			(stroke
				(width 0.1)
				(type default)
			)
			(layer "F.Fab")
		)
		(fp_line
			(start -0.12065 0.2794)
			(end -0.12065 0.3048)
			(stroke
				(width 0.1)
				(type default)
			)
			(layer "F.Fab")
		)
		(fp_line
			(start 0.120396 0.2794)
			(end -0.12065 0.2794)
			(stroke
				(width 0.1)
				(type default)
			)
			(layer "F.Fab")
		)
		(fp_line
			(start -0.12065 -0.2794)
			(end 0.12065 -0.2794)
			(stroke
				(width 0.1)
				(type default)
			)
			(layer "F.Fab")
		)
		(fp_line
			(start 0.12065 -0.2794)
			(end 0.12065 -0.3048)
			(stroke
				(width 0.1)
				(type default)
			)
			(layer "F.Fab")
		)
		(fp_line
			(start 0.12065 -0.3048)
			(end 0.67945 -0.3048)
			(stroke
				(width 0.1)
				(type default)
			)
			(layer "F.Fab")
		)
		(fp_line
			(start 0.67945 -0.3048)
			(end 0.67945 0.3048)
			(stroke
				(width 0.1)
				(type default)
			)
			(layer "F.Fab")
		)
		(fp_line
			(start -0.67945 -0.305054)
			(end -0.12065 -0.305054)
			(stroke
				(width 0.1)
				(type default)
			)
			(layer "F.Fab")
		)
		(fp_line
			(start -0.12065 -0.305054)
			(end -0.12065 -0.2794)
			(stroke
				(width 0.1)
				(type default)
			)
			(layer "F.Fab")
		)
		(pad "1" smd circle
			(at -0.40005 0 270)
			(size 0 0)
			(layers "F.Cu" "F.Mask" "F.Paste")
			(net "SW_PVCCIN_CPU1_BOOT3_R")
		)
		(pad "2" smd circle
			(at 0.40005 0 270)
			(size 0 0)
			(layers "F.Cu" "F.Mask" "F.Paste")
			(net "SW_PVCCIN_CPU1_BOOTR3")
		)
	)
	(footprint ""
		(layer "F.Cu")
		(at 31.53918 -122.380502 90)
		(property "Reference" "R1662"
			(at 0 0 90)
			(layer "F.SilkS")
			(hide yes)
			(effects
				(font
					(size 1.27 1.27)
				)
			)
		)
		(property "Value" ""
			(at 0 0 90)
			(layer "F.Fab")
			(effects
				(font
					(size 1.27 1.27)
				)
			)
		)
		(duplicate_pad_numbers_are_jumpers no)
		(fp_line
			(start 0.7874 -0.4064)
			(end 0.7874 0.4064)
			(stroke
				(width 0.1524)
				(type default)
			)
			(layer "F.SilkS")
		)
		(fp_line
			(start -0.7874 -0.4064)
			(end 0.7874 -0.4064)
			(stroke
				(width 0.1524)
				(type default)
			)
			(layer "F.SilkS")
		)
		(fp_line
			(start 0.7874 0.4064)
			(end -0.7874 0.4064)
			(stroke
				(width 0.1524)
				(type default)
			)
			(layer "F.SilkS")
		)
		(fp_line
			(start -0.7874 0.4064)
			(end -0.7874 -0.4064)
			(stroke
				(width 0.1524)
				(type default)
			)
			(layer "F.SilkS")
		)
		(fp_line
			(start -0.12065 -0.305054)
			(end -0.12065 -0.2794)
			(stroke
				(width 0.1)
				(type default)
			)
			(layer "F.Fab")
		)
		(fp_line
			(start -0.67945 -0.305054)
			(end -0.12065 -0.305054)
			(stroke
				(width 0.1)
				(type default)
			)
			(layer "F.Fab")
		)
		(fp_line
			(start 0.67945 -0.3048)
			(end 0.67945 0.3048)
			(stroke
				(width 0.1)
				(type default)
			)
			(layer "F.Fab")
		)
		(fp_line
			(start 0.12065 -0.3048)
			(end 0.67945 -0.3048)
			(stroke
				(width 0.1)
				(type default)
			)
			(layer "F.Fab")
		)
		(fp_line
			(start 0.12065 -0.2794)
			(end 0.12065 -0.3048)
			(stroke
				(width 0.1)
				(type default)
			)
			(layer "F.Fab")
		)
		(fp_line
			(start -0.12065 -0.2794)
			(end 0.12065 -0.2794)
			(stroke
				(width 0.1)
				(type default)
			)
			(layer "F.Fab")
		)
		(fp_line
			(start 0.120396 0.2794)
			(end -0.12065 0.2794)
			(stroke
				(width 0.1)
				(type default)
			)
			(layer "F.Fab")
		)
		(fp_line
			(start -0.12065 0.2794)
			(end -0.12065 0.3048)
			(stroke
				(width 0.1)
				(type default)
			)
			(layer "F.Fab")
		)
		(fp_line
			(start 0.67945 0.3048)
			(end 0.120396 0.3048)
			(stroke
				(width 0.1)
				(type default)
			)
			(layer "F.Fab")
		)
		(fp_line
			(start 0.120396 0.3048)
			(end 0.120396 0.2794)
			(stroke
				(width 0.1)
				(type default)
			)
			(layer "F.Fab")
		)
		(fp_line
			(start -0.12065 0.3048)
			(end -0.67945 0.3048)
			(stroke
				(width 0.1)
				(type default)
			)
			(layer "F.Fab")
		)
		(fp_line
			(start -0.67945 0.3048)
			(end -0.67945 -0.305054)
			(stroke
				(width 0.1)
				(type default)
			)
			(layer "F.Fab")
		)
		(pad "1" smd circle
			(at -0.40005 0 90)
			(size 0 0)
			(layers "F.Cu" "F.Mask" "F.Paste")
			(net "SMB_VR_3V3AUX_SDA")
		)
		(pad "2" smd circle
			(at 0.40005 0 90)
			(size 0 0)
			(layers "F.Cu" "F.Mask" "F.Paste")
			(net "SMB_VR_3V3AUX_SDA_R")
		)
	)
	(footprint ""
		(layer "F.Cu")
		(at 60.127388 -32.287972 180)
		(property "Reference" "R3868"
			(at 0 0 180)
			(layer "F.SilkS")
			(hide yes)
			(effects
				(font
					(size 1.27 1.27)
				)
			)
		)
		(property "Value" ""
			(at 0 0 180)
			(layer "F.Fab")
			(effects
				(font
					(size 1.27 1.27)
				)
			)
		)
		(duplicate_pad_numbers_are_jumpers no)
		(fp_line
			(start 0.7874 0.4064)
			(end -0.7874 0.4064)
			(stroke
				(width 0.1524)
				(type default)
			)
			(layer "F.SilkS")
		)
		(fp_line
			(start 0.7874 -0.4064)
			(end 0.7874 0.4064)
			(stroke
				(width 0.1524)
				(type default)
			)
			(layer "F.SilkS")
		)
		(fp_line
			(start -0.7874 0.4064)
			(end -0.7874 -0.4064)
			(stroke
				(width 0.1524)
				(type default)
			)
			(layer "F.SilkS")
		)
		(fp_line
			(start -0.7874 -0.4064)
			(end 0.7874 -0.4064)
			(stroke
				(width 0.1524)
				(type default)
			)
			(layer "F.SilkS")
		)
		(fp_line
			(start 0.67945 0.3048)
			(end 0.120396 0.3048)
			(stroke
				(width 0.1)
				(type default)
			)
			(layer "F.Fab")
		)
		(fp_line
			(start 0.67945 -0.3048)
			(end 0.67945 0.3048)
			(stroke
				(width 0.1)
				(type default)
			)
			(layer "F.Fab")
		)
		(fp_line
			(start 0.12065 -0.2794)
			(end 0.12065 -0.3048)
			(stroke
				(width 0.1)
				(type default)
			)
			(layer "F.Fab")
		)
		(fp_line
			(start 0.12065 -0.3048)
			(end 0.67945 -0.3048)
			(stroke
				(width 0.1)
				(type default)
			)
			(layer "F.Fab")
		)
		(fp_line
			(start 0.120396 0.3048)
			(end 0.120396 0.2794)
			(stroke
				(width 0.1)
				(type default)
			)
			(layer "F.Fab")
		)
		(fp_line
			(start 0.120396 0.2794)
			(end -0.12065 0.2794)
			(stroke
				(width 0.1)
				(type default)
			)
			(layer "F.Fab")
		)
		(fp_line
			(start -0.12065 0.3048)
			(end -0.67945 0.3048)
			(stroke
				(width 0.1)
				(type default)
			)
			(layer "F.Fab")
		)
		(fp_line
			(start -0.12065 0.2794)
			(end -0.12065 0.3048)
			(stroke
				(width 0.1)
				(type default)
			)
			(layer "F.Fab")
		)
		(fp_line
			(start -0.12065 -0.2794)
			(end 0.12065 -0.2794)
			(stroke
				(width 0.1)
				(type default)
			)
			(layer "F.Fab")
		)
		(fp_line
			(start -0.12065 -0.305054)
			(end -0.12065 -0.2794)
			(stroke
				(width 0.1)
				(type default)
			)
			(layer "F.Fab")
		)
		(fp_line
			(start -0.67945 0.3048)
			(end -0.67945 -0.305054)
			(stroke
				(width 0.1)
				(type default)
			)
			(layer "F.Fab")
		)
		(fp_line
			(start -0.67945 -0.305054)
			(end -0.12065 -0.305054)
			(stroke
				(width 0.1)
				(type default)
			)
			(layer "F.Fab")
		)
		(pad "1" smd rect
			(at -0.40005 0)
			(size 0.4572 0.508)
			(layers "F.Cu" "F.Mask" "F.Paste")
			(net "P12V_OCP_SENSE_2")
		)
		(pad "2" smd rect
			(at 0.40005 0)
			(size 0.4572 0.508)
			(layers "F.Cu" "F.Mask" "F.Paste")
			(net "P12V_OCP_V3_2_ISENSE_MAM_TIC")
		)
	)
	(footprint ""
		(layer "F.Cu")
		(at 155.690824 -51.531012)
		(property "Reference" "C2013"
			(at 0 0 0)
			(layer "F.SilkS")
			(hide yes)
			(effects
				(font
					(size 1.27 1.27)
				)
			)
		)
		(property "Value" ""
			(at 0 0 0)
			(layer "F.Fab")
			(effects
				(font
					(size 1.27 1.27)
				)
			)
		)
		(duplicate_pad_numbers_are_jumpers no)
		(fp_line
			(start -0.7874 -0.4064)
			(end 0.7874 -0.4064)
			(stroke
				(width 0.1524)
				(type default)
			)
			(layer "F.SilkS")
		)
		(fp_line
			(start -0.7874 0.4064)
			(end -0.7874 -0.4064)
			(stroke
				(width 0.1524)
				(type default)
			)
			(layer "F.SilkS")
		)
		(fp_line
			(start 0.7874 -0.4064)
			(end 0.7874 0.4064)
			(stroke
				(width 0.1524)
				(type default)
			)
			(layer "F.SilkS")
		)
		(fp_line
			(start 0.7874 0.4064)
			(end -0.7874 0.4064)
			(stroke
				(width 0.1524)
				(type default)
			)
			(layer "F.SilkS")
		)
		(fp_line
			(start -0.67945 -0.305054)
			(end -0.12065 -0.305054)
			(stroke
				(width 0.1)
				(type default)
			)
			(layer "F.Fab")
		)
		(fp_line
			(start -0.67945 0.3048)
			(end -0.67945 -0.305054)
			(stroke
				(width 0.1)
				(type default)
			)
			(layer "F.Fab")
		)
		(fp_line
			(start -0.12065 -0.305054)
			(end -0.12065 -0.2794)
			(stroke
				(width 0.1)
				(type default)
			)
			(layer "F.Fab")
		)
		(fp_line
			(start -0.12065 -0.2794)
			(end 0.12065 -0.2794)
			(stroke
				(width 0.1)
				(type default)
			)
			(layer "F.Fab")
		)
		(fp_line
			(start -0.12065 0.2794)
			(end -0.12065 0.3048)
			(stroke
				(width 0.1)
				(type default)
			)
			(layer "F.Fab")
		)
		(fp_line
			(start -0.12065 0.3048)
			(end -0.67945 0.3048)
			(stroke
				(width 0.1)
				(type default)
			)
			(layer "F.Fab")
		)
		(fp_line
			(start 0.120396 0.2794)
			(end -0.12065 0.2794)
			(stroke
				(width 0.1)
				(type default)
			)
			(layer "F.Fab")
		)
		(fp_line
			(start 0.120396 0.3048)
			(end 0.120396 0.2794)
			(stroke
				(width 0.1)
				(type default)
			)
			(layer "F.Fab")
		)
		(fp_line
			(start 0.12065 -0.3048)
			(end 0.67945 -0.3048)
			(stroke
				(width 0.1)
				(type default)
			)
			(layer "F.Fab")
		)
		(fp_line
			(start 0.12065 -0.2794)
			(end 0.12065 -0.3048)
			(stroke
				(width 0.1)
				(type default)
			)
			(layer "F.Fab")
		)
		(fp_line
			(start 0.67945 -0.3048)
			(end 0.67945 0.3048)
			(stroke
				(width 0.1)
				(type default)
			)
			(layer "F.Fab")
		)
		(fp_line
			(start 0.67945 0.3048)
			(end 0.120396 0.3048)
			(stroke
				(width 0.1)
				(type default)
			)
			(layer "F.Fab")
		)
		(pad "1" smd circle
			(at -0.40005 0)
			(size 0 0)
			(layers "F.Cu" "F.Mask" "F.Paste")
			(net "P3V3_AUX")
		)
		(pad "2" smd circle
			(at 0.40005 0)
			(size 0 0)
			(layers "F.Cu" "F.Mask" "F.Paste")
			(net "GND")
		)
	)
	(footprint ""
		(layer "F.Cu")
		(at 24.804878 -17.623536 90)
		(property "Reference" "C813"
			(at 0 0 90)
			(layer "F.SilkS")
			(hide yes)
			(effects
				(font
					(size 1.27 1.27)
				)
			)
		)
		(property "Value" ""
			(at 0 0 90)
			(layer "F.Fab")
			(effects
				(font
					(size 1.27 1.27)
				)
			)
		)
		(duplicate_pad_numbers_are_jumpers no)
		(fp_line
			(start 0.299974 -0.150114)
			(end 0.299974 0.150114)
			(stroke
				(width 0.1)
				(type default)
			)
			(layer "F.Fab")
		)
		(fp_line
			(start -0.299974 -0.150114)
			(end 0.299974 -0.150114)
			(stroke
				(width 0.1)
				(type default)
			)
			(layer "F.Fab")
		)
		(fp_line
			(start 0.299974 0.150114)
			(end -0.299974 0.150114)
			(stroke
				(width 0.1)
				(type default)
			)
			(layer "F.Fab")
		)
		(fp_line
			(start -0.299974 0.150114)
			(end -0.299974 -0.150114)
			(stroke
				(width 0.1)
				(type default)
			)
			(layer "F.Fab")
		)
		(pad "1" smd rect
			(at -0.2667 0 90)
			(size 0.3048 0.381)
			(layers "F.Cu" "F.Mask" "F.Paste")
			(net "P5E_CPU1_PE1_TX_C_DP<12>")
		)
		(pad "2" smd rect
			(at 0.2667 0 90)
			(size 0.3048 0.381)
			(layers "F.Cu" "F.Mask" "F.Paste")
			(net "P5E_CPU1_PE1_TX_DP<12>")
		)
	)
	(footprint ""
		(layer "F.Cu")
		(at 79.75473 -59.372246 90)
		(property "Reference" "PR3812"
			(at 0 0 90)
			(layer "F.SilkS")
			(hide yes)
			(effects
				(font
					(size 1.27 1.27)
				)
			)
		)
		(property "Value" ""
			(at 0 0 90)
			(layer "F.Fab")
			(effects
				(font
					(size 1.27 1.27)
				)
			)
		)
		(duplicate_pad_numbers_are_jumpers no)
		(fp_line
			(start 0.7874 -0.4064)
			(end 0.7874 0.4064)
			(stroke
				(width 0.1524)
				(type default)
			)
			(layer "F.SilkS")
		)
		(fp_line
			(start -0.7874 -0.4064)
			(end 0.7874 -0.4064)
			(stroke
				(width 0.1524)
				(type default)
			)
			(layer "F.SilkS")
		)
		(fp_line
			(start 0.7874 0.4064)
			(end -0.7874 0.4064)
			(stroke
				(width 0.1524)
				(type default)
			)
			(layer "F.SilkS")
		)
		(fp_line
			(start -0.7874 0.4064)
			(end -0.7874 -0.4064)
			(stroke
				(width 0.1524)
				(type default)
			)
			(layer "F.SilkS")
		)
		(fp_line
			(start -0.12065 -0.305054)
			(end -0.12065 -0.2794)
			(stroke
				(width 0.1)
				(type default)
			)
			(layer "F.Fab")
		)
		(fp_line
			(start -0.67945 -0.305054)
			(end -0.12065 -0.305054)
			(stroke
				(width 0.1)
				(type default)
			)
			(layer "F.Fab")
		)
		(fp_line
			(start 0.67945 -0.3048)
			(end 0.67945 0.3048)
			(stroke
				(width 0.1)
				(type default)
			)
			(layer "F.Fab")
		)
		(fp_line
			(start 0.12065 -0.3048)
			(end 0.67945 -0.3048)
			(stroke
				(width 0.1)
				(type default)
			)
			(layer "F.Fab")
		)
		(fp_line
			(start 0.12065 -0.2794)
			(end 0.12065 -0.3048)
			(stroke
				(width 0.1)
				(type default)
			)
			(layer "F.Fab")
		)
		(fp_line
			(start -0.12065 -0.2794)
			(end 0.12065 -0.2794)
			(stroke
				(width 0.1)
				(type default)
			)
			(layer "F.Fab")
		)
		(fp_line
			(start 0.120396 0.2794)
			(end -0.12065 0.2794)
			(stroke
				(width 0.1)
				(type default)
			)
			(layer "F.Fab")
		)
		(fp_line
			(start -0.12065 0.2794)
			(end -0.12065 0.3048)
			(stroke
				(width 0.1)
				(type default)
			)
			(layer "F.Fab")
		)
		(fp_line
			(start 0.67945 0.3048)
			(end 0.120396 0.3048)
			(stroke
				(width 0.1)
				(type default)
			)
			(layer "F.Fab")
		)
		(fp_line
			(start 0.120396 0.3048)
			(end 0.120396 0.2794)
			(stroke
				(width 0.1)
				(type default)
			)
			(layer "F.Fab")
		)
		(fp_line
			(start -0.12065 0.3048)
			(end -0.67945 0.3048)
			(stroke
				(width 0.1)
				(type default)
			)
			(layer "F.Fab")
		)
		(fp_line
			(start -0.67945 0.3048)
			(end -0.67945 -0.305054)
			(stroke
				(width 0.1)
				(type default)
			)
			(layer "F.Fab")
		)
		(pad "1" smd circle
			(at -0.40005 0 90)
			(size 0 0)
			(layers "F.Cu" "F.Mask" "F.Paste")
			(net "P3V3_OCP_OV_2")
		)
		(pad "2" smd circle
			(at 0.40005 0 90)
			(size 0 0)
			(layers "F.Cu" "F.Mask" "F.Paste")
			(net "GND")
		)
	)
)
